# S9S_MB_2U (Grand Teton) — schematic parts with pin connectivity, parts 5876–5876 of 6093; source: Cadence DE-HDL packaged netlist (pstxprt.dat, pstxnet.dat, pstchip.dat)

U1  SOCKET4677_AZIF0045P001C01CS  SOCKET4677_AZIF0045-P001C01CS IO  pkg SOCKET4677_82X64-5XA_H466  page 44  (pins 2290-2616 of 4677)
  CW64  VCCINFAON55  POWER  = PVCCINFAON_CPU1
  CW66  VCCINFAON21  POWER  = PVCCINFAON_CPU1
  CW68  RSVD150  BI  = CPU1_RSVD<144>
  CW70  VSS595  POWER  = GND
  CW72  VSS840  POWER  = GND
  CW74  UPI3_TX_DP22  OUT  = NC
  CW76  UPI3_TX_DN12  OUT  = NC
  CW78  VSS843  POWER  = GND
  CW80  UPI3_RX_DN19  IN  = GND
  CW82  UPI3_RX_DP17  IN  = GND
  CW84  VSS846  POWER  = GND
  CW86  PE3_TX_DP13  OUT  = P5E_CPU1_PE3_TX_DP<13>
  CW88  VSS848  POWER  = GND
  CW90  PE3_RX_DP14  IN  = P5E_CPU1_PE3_RX_DP<14>
  CY2  UPI1_RX_DN14  IN  = UPI_CPU0_CPU1_P0P1_DN<14>
  CY4  VSS611  POWER  = GND
  CY6  UPI1_TX_DN13  OUT  = UPI_CPU1_CPU0_P1P0_DN<13>
  CY8  VSS860  POWER  = GND
  CY10  PE2_RX_DN1  IN  = P5E_CPU1_PE2_RX_DN<1>
  CY12  VSS851  POWER  = GND
  CY14  PE2_TX_DP2  OUT  = P5E_CPU1_PE2_TX_DP<2>
  CY16  VSS852  POWER  = GND
  CY18  VSS853  POWER  = GND
  CY20  CD_INIT_ERROR  OUT  = FM_S3M_CPU1_CPLD_CRC_ERROR
  CY22  TEST_5  BI  = PD_JTAG_CPU1_PLD_TCK
  CY24  RSVD151  BI  = NC_CPU1_DDR45_VIEWDIG0
  CY26  VSS854  POWER  = GND
  CY28  BCLK1_DN  IN  = CLK_100M_DB2000_CPU1_BCLK1_DN
  CY30  VSS855  POWER  = GND
  CY32  XTAL_CLK_DP  IN  = CLK_25M_NSSC_CPU1_DP
  CY34  VCCD_HV26  POWER  = PVCCD_HV_CPU1
  CY36  VCCD_HV27  POWER  = PVCCD_HV_CPU1
  CY38  RSVD152  BI  = NC_CPU1_DDR45_VIEWDIG1
  CY40  PMDOWN_PCH  BI  = TP_H_CPU1_PMDOWN_PCH_R
  CY42  DDR45_RESET_N  OUT  = RST_CPU1_DRAM_EF_N
  CY44  DDR45_DRAM_PWR_OK  IN  = PWRGD_DRAMPWRGD_CPU1_EF_LVC1_R
  CY47  DDR4_ALERT_N  IN  = M_E_CPU1_ALERT_N
  CY49  RSVD153  BI  = NC_CPU1_DDR67_VIEWDIG1
  CY51  DDR7_ALERT_N  IN  = M_H_CPU1_ALERT_N
  CY53  VCCD_HV28  POWER  = PVCCD_HV_CPU1
  CY55  DDR67_RESET_N  OUT  = RST_CPU1_DRAM_GH_N
  CY57  RSVD154  BI  = NC_CPU1_VIEWPIN_GNR3
  CY59  LEGACY_SKT  IN  = PU_CPU1_LEGACY_SKT
  CY61  SOCKET_ID1  IN  = PU_CPU1_SOCKET_ID1
  CY63  VSS856  POWER  = GND
  CY65  VCCINFAON22  POWER  = PVCCINFAON_CPU1
  CY67  VCCINFAON23  POWER  = PVCCINFAON_CPU1
  CY69  RSVD155  BI  = NC_UART_IBL_CPU1_RXD
  CY71  RSVD156  BI  = NC_UART_IBL_CPU1_RTS
  CY73  VSS858  POWER  = GND
  CY75  VCCFA_EHV_FIVRA42  POWER  = PVCCFA_EHV_FIVRA_CPU1
  CY77  VSS859  POWER  = GND
  CY79  VCCFA_EHV_FIVRA43  POWER  = PVCCFA_EHV_FIVRA_CPU1
  CY81  VSS862  POWER  = GND
  CY83  VSS863  POWER  = GND
  CY85  VCCFA_EHV_FIVRA44  POWER  = PVCCFA_EHV_FIVRA_CPU1
  CY87  PE3_TX_DN12  OUT  = P5E_CPU1_PE3_TX_DN<12>
  CY89  VCCFA_EHV_FIVRA45  POWER  = PVCCFA_EHV_FIVRA_CPU1
  CY91  PE3_RX_DP13  IN  = P5E_CPU1_PE3_RX_DP<13>
  D4  RSVD157  BI  = CPU1_RSVD<153>
  D6  VSS899  POWER  = GND
  D8  VSS663  POWER  = GND
  D10  VSS864  POWER  = GND
  D12  VSS865  POWER  = GND
  D14  VSS866  POWER  = GND
  D16  VSS868  POWER  = GND
  D18  VSS869  POWER  = GND
  D20  VSS871  POWER  = GND
  D22  VSS873  POWER  = GND
  D24  VSS874  POWER  = GND
  D26  VSS875  POWER  = GND
  D28  VSS876  POWER  = GND
  D30  VSS877  POWER  = GND
  D32  VSS878  POWER  = GND
  D34  VSS879  POWER  = GND
  D36  VSS881  POWER  = GND
  D38  VSS884  POWER  = GND
  D40  VSS885  POWER  = GND
  D42  VSS886  POWER  = GND
  D44  VSS888  POWER  = GND
  D47  VSS889  POWER  = GND
  D49  VSS891  POWER  = GND
  D51  VSS892  POWER  = GND
  D53  VSS895  POWER  = GND
  D55  VSS896  POWER  = GND
  D57  VSS897  POWER  = GND
  D59  VSS898  POWER  = GND
  D61  VSS900  POWER  = GND
  D63  VSS657  POWER  = GND
  D65  VSS658  POWER  = GND
  D67  VSS659  POWER  = GND
  D69  VSS901  POWER  = GND
  D71  VSS902  POWER  = GND
  D73  DDR0_SA_DQ18  BI  = M_A_CPU1_SA_DQ<18>
  D75  DDR0_SA_DQ5  BI  = M_A_CPU1_SA_DQ<5>
  D77  DDR0_SA_DQS_DP0  BI  = M_A_CPU1_SA_DQS_DP<0>
  D79  VSS662  POWER  = GND
  D81  VSS906  POWER  = GND
  D83  VSS907  POWER  = GND
  D85  UPI2_TX_DP0  OUT  = UPI_CPU1_CPU0_P2P2_DP<0>
  D87  UPI2_TX_DN2  OUT  = UPI_CPU1_CPU0_P2P2_DN<2>
  DA1  UPI1_RX_DP13  IN  = UPI_CPU0_CPU1_P0P1_DP<13>
  DA3  VCCINFAON56  POWER  = PVCCINFAON_CPU1
  DA5  UPI1_TX_DN12  OUT  = UPI_CPU1_CPU0_P1P0_DN<12>
  DA7  VCCINFAON57  POWER  = PVCCINFAON_CPU1
  DA9  PE2_RX_DN2  IN  = P5E_CPU1_PE2_RX_DN<2>
  DA11  VCCINFAON24  POWER  = PVCCINFAON_CPU1
  DA13  PE2_TX_DN2  OUT  = P5E_CPU1_PE2_TX_DN<2>
  DA15  VCCINFAON25  POWER  = PVCCINFAON_CPU1
  DA17  DDR7_SB_DQ29  BI  = M_H_CPU1_SB_DQ<29>
  DA19  VSS910  POWER  = GND
  DA21  VCCINFAON53  POWER  = PVCCINFAON_CPU1
  DA23  VSS911  POWER  = GND
  DA25  VSS912  POWER  = GND
  DA27  BCLK3_DP  IN  = CLK_100M_DB2000_CPU1_BCLK3_DP
  DA29  VSS913  POWER  = GND
  DA31  VSS914  POWER  = GND
  DA33  VSS915  POWER  = GND
  DA35  VSS916  POWER  = GND
  DA37  VSS917  POWER  = GND
  DA39  PMSYNC_PCH  BI  = TP_H_CPU1_PMSYNC_PCH_INTRP_R
  DA41  VSS918  POWER  = GND
  DA43  VSS679  POWER  = GND
  DA45  RSVD158  BI  = NC_CPU1_DDR67_VIEWDIG0
  DA48  VSS919  POWER  = GND
  DA50  VSS920  POWER  = GND
  DA52  PROCDIS_N  IN  = PD_CPU1_PROCDIS_COD_GTL_N
  DA54  VSS921  POWER  = GND
  DA56  VSS922  POWER  = GND
  DA58  VSS923  POWER  = GND
  DA60  VSS924  POWER  = GND
  DA62  VSS925  POWER  = GND
  DA64  VCCINFAON26  POWER  = PVCCINFAON_CPU1
  DA66  VSS926  POWER  = GND
  DA68  VSS690  POWER  = GND
  DA70  RSVD159  BI  = TP_CPU1_SPARE4
  DA72  VSS927  POWER  = GND
  DA74  VSS928  POWER  = GND
  DA76  UPI3_TX_DP12  OUT  = NC
  DA78  UPI3_RX_DN23  IN  = GND
  DA80  VSS929  POWER  = GND
  DA82  VSS930  POWER  = GND
  DA84  VSS931  POWER  = GND
  DA86  PE3_TX_DP12  OUT  = P5E_CPU1_PE3_TX_DP<12>
  DA88  VSS932  POWER  = GND
  DA90  PE3_RX_DN13  IN  = P5E_CPU1_PE3_RX_DN<13>
  DB2  UPI1_RX_DN13  IN  = UPI_CPU0_CPU1_P0P1_DN<13>
  DB4  VSS939  POWER  = GND
  DB6  UPI1_TX_DP12  OUT  = UPI_CPU1_CPU0_P1P0_DP<12>
  DB8  VSS947  POWER  = GND
  DB10  PE2_RX_DP2  IN  = P5E_CPU1_PE2_RX_DP<2>
  DB12  VSS933  POWER  = GND
  DB14  PE2_TX_DN3  OUT  = P5E_CPU1_PE2_TX_DN<3>
  DB16  VSS699  POWER  = GND
  DB18  DDR7_SB_DQS_DN3  BI  = M_H_CPU1_SB_DQS_DN<3>
  DB20  VSS700  POWER  = GND
  DB22  VSS935  POWER  = GND
  DB24  DDR7_SB_DQS_DP1  BI  = M_H_CPU1_SB_DQS_DP<1>
  DB26  VSS702  POWER  = GND
  DB28  VSS936  POWER  = GND
  DB30  DDR7_SB_DQS_DP0  BI  = M_H_CPU1_SB_DQS_DP<0>
  DB32  VSS937  POWER  = GND
  DB34  VSS705  POWER  = GND
  DB36  DDR7_SB_DQS_DP9  BI  = M_H_CPU1_SB_DQS_DP<9>
  DB38  VSS938  POWER  = GND
  DB40  VSS940  POWER  = GND
  DB42  DDR7_CLK_DP1  OUT  = M_H_CPU1_CLK_DP<1>
  DB44  VSS709  POWER  = GND
  DB47  VSS941  POWER  = GND
  DB49  DDR7_SA_CA0  OUT  = M_H_CPU1_SA_CA<0>
  DB51  VSS711  POWER  = GND
  DB53  VSS712  POWER  = GND
  DB55  DDR7_SA_DQS_DP4  BI  = M_H_CPU1_SA_DQS_DP<4>
  DB57  VSS942  POWER  = GND
  DB59  VSS714  POWER  = GND
  DB61  DDR7_SA_DQS_DP3  BI  = M_H_CPU1_SA_DQS_DP<3>
  DB63  VSS715  POWER  = GND
  DB65  VSS943  POWER  = GND
  DB67  DDR7_SA_DQS_DP2  BI  = M_H_CPU1_SA_DQS_DP<2>
  DB69  VSS717  POWER  = GND
  DB71  VSS944  POWER  = GND
  DB73  DDR7_SA_DQS_DN1  BI  = M_H_CPU1_SA_DQS_DN<1>
  DB75  VSS719  POWER  = GND
  DB77  VSS946  POWER  = GND
  DB79  UPI3_RX_DP23  IN  = GND
  DB81  UPI3_RX_DN15  IN  = GND
  DB83  UPI3_RX_DP14  IN  = GND
  DB85  PE3_TX_DN11  OUT  = P5E_CPU1_PE3_TX_DN<11>
  DB87  VSS948  POWER  = GND
  DB89  PE3_RX_DN12  IN  = P5E_CPU1_PE3_RX_DN<12>
  DB91  VSS723  POWER  = GND
  DC1  VSS724  POWER  = GND
  DC3  UPI1_RX_DP12  IN  = UPI_CPU0_CPU1_P0P1_DP<12>
  DC5  VSS953  POWER  = GND
  DC7  UPI1_TX_DP11  OUT  = UPI_CPU1_CPU0_P1P0_DP<11>
  DC9  VSS963  POWER  = GND
  DC11  PE2_RX_DP3  IN  = P5E_CPU1_PE2_RX_DP<3>
  DC13  VSS725  POWER  = GND
  DC15  PE2_TX_DP3  OUT  = P5E_CPU1_PE2_TX_DP<3>
  DC17  DDR7_SB_DQ31  BI  = M_H_CPU1_SB_DQ<31>
  DC19  DDR7_SB_DQ25  BI  = M_H_CPU1_SB_DQ<25>
  DC21  VSS726  POWER  = GND
  DC23  DDR7_SB_DQ12  BI  = M_H_CPU1_SB_DQ<12>
  DC25  DDR7_SB_DQ9  BI  = M_H_CPU1_SB_DQ<9>
  DC27  VSS949  POWER  = GND
  DC29  DDR7_SB_DQ4  BI  = M_H_CPU1_SB_DQ<4>
  DC31  DDR7_SB_DQ1  BI  = M_H_CPU1_SB_DQ<1>
  DC33  VSS950  POWER  = GND
  DC35  DDR7_SB_ECC0  BI  = M_H_CPU1_SB_CB<0>
  DC37  DDR7_SB_ECC7  BI  = M_H_CPU1_SB_CB<7>
  DC39  VSS951  POWER  = GND
  DC41  DDR7_SA_CA6  OUT  = M_H_CPU1_SA_CA<6>
  DC43  DDR4_A_RSP1  IN  = M_E_CPU1_SA_RSP<1>
  DC45  VSS952  POWER  = GND
  DC48  DDR7_SA_CA2  OUT  = M_H_CPU1_SA_CA<2>
  DC50  DDR7_SA_CS_N3  OUT  = M_H_CPU1_SA_CS_N<3>
  DC52  VSS735  POWER  = GND
  DC54  DDR7_SA_ECC4  BI  = M_H_CPU1_SA_CB<4>
  DC56  DDR7_SA_ECC1  BI  = M_H_CPU1_SA_CB<1>
  DC58  VSS738  POWER  = GND
  DC60  DDR7_SA_DQ28  BI  = M_H_CPU1_SA_DQ<28>
  DC62  DDR7_SA_DQ25  BI  = M_H_CPU1_SA_DQ<25>
  DC64  VSS739  POWER  = GND
  DC66  DDR7_SA_DQ20  BI  = M_H_CPU1_SA_DQ<20>
  DC68  DDR7_SA_DQ17  BI  = M_H_CPU1_SA_DQ<17>
  DC70  VSS954  POWER  = GND
  DC72  DDR7_SA_DQ12  BI  = M_H_CPU1_SA_DQ<12>
  DC74  DDR7_SA_DQ9  BI  = M_H_CPU1_SA_DQ<9>
  DC76  VSS956  POWER  = GND
  DC78  VSS958  POWER  = GND
  DC80  VSS960  POWER  = GND
  DC82  UPI3_RX_DN14  IN  = GND
  DC84  VSS961  POWER  = GND
  DC86  PE3_TX_DP11  OUT  = P5E_CPU1_PE3_TX_DP<11>
  DC88  VSS962  POWER  = GND
  DC90  PE3_RX_DP12  IN  = P5E_CPU1_PE3_RX_DP<12>
  DD2  UPI1_RX_DN12  IN  = UPI_CPU0_CPU1_P0P1_DN<12>
  DD4  VSS964  POWER  = GND
  DD6  UPI1_TX_DN11  OUT  = UPI_CPU1_CPU0_P1P0_DN<11>
  DD8  VSS967  POWER  = GND
  DD10  PE2_RX_DN3  IN  = P5E_CPU1_PE2_RX_DN<3>
  DD12  VSS747  POWER  = GND
  DD14  PE2_TX_DP4  OUT  = P5E_CPU1_PE2_TX_DP<4>
  DD16  VSS748  POWER  = GND
  DD18  DDR7_SB_DQS_DP3  BI  = M_H_CPU1_SB_DQS_DP<3>
  DD20  DDR7_SB_DQ24  BI  = M_H_CPU1_SB_DQ<24>
  DD22  DDR7_SB_DQ13  BI  = M_H_CPU1_SB_DQ<13>
  DD24  DDR7_SB_DQS_DN1  BI  = M_H_CPU1_SB_DQS_DN<1>
  DD26  DDR7_SB_DQ8  BI  = M_H_CPU1_SB_DQ<8>
  DD28  DDR7_SB_DQ7  BI  = M_H_CPU1_SB_DQ<7>
  DD30  DDR7_SB_DQS_DN0  BI  = M_H_CPU1_SB_DQS_DN<0>
  DD32  DDR7_SB_DQ0  BI  = M_H_CPU1_SB_DQ<0>
  DD34  DDR7_SB_ECC1  BI  = M_H_CPU1_SB_CB<1>
  DD36  DDR7_SB_DQS_DN9  BI  = M_H_CPU1_SB_DQS_DN<9>
  DD38  DDR7_SB_ECC6  BI  = M_H_CPU1_SB_CB<6>
  DD40  DDR7_SA_PAR  OUT  = M_H_CPU1_SA_PAR
  DD42  DDR7_CLK_DN1  OUT  = M_H_CPU1_CLK_DN<1>
  DD44  DDR4_A_RSP0  IN  = M_E_CPU1_SA_RSP<0>
  DD47  DDR7_SA_CA4  OUT  = M_H_CPU1_SA_CA<4>
  DD49  VSS753  POWER  = GND
  DD51  DDR7_SA_CS_N2  OUT  = M_H_CPU1_SA_CS_N<2>
  DD53  DDR7_SA_ECC5  BI  = M_H_CPU1_SA_CB<5>
  DD55  DDR7_SA_DQS_DN4  BI  = M_H_CPU1_SA_DQS_DN<4>
  DD57  DDR7_SA_ECC0  BI  = M_H_CPU1_SA_CB<0>
  DD59  DDR7_SA_DQ29  BI  = M_H_CPU1_SA_DQ<29>
  DD61  DDR7_SA_DQS_DN3  BI  = M_H_CPU1_SA_DQS_DN<3>
  DD63  DDR7_SA_DQ24  BI  = M_H_CPU1_SA_DQ<24>
  DD65  DDR7_SA_DQ21  BI  = M_H_CPU1_SA_DQ<21>
  DD67  DDR7_SA_DQS_DN2  BI  = M_H_CPU1_SA_DQS_DN<2>
  DD69  DDR7_SA_DQ16  BI  = M_H_CPU1_SA_DQ<16>
  DD71  DDR7_SA_DQ13  BI  = M_H_CPU1_SA_DQ<13>
  DD73  DDR7_SA_DQS_DP1  BI  = M_H_CPU1_SA_DQS_DP<1>
  DD75  DDR7_SA_DQ8  BI  = M_H_CPU1_SA_DQ<8>
  DD77  VCCFA_EHV_FIVRA46  POWER  = PVCCFA_EHV_FIVRA_CPU1
  DD79  VSS965  POWER  = GND
  DD81  UPI3_RX_DP15  IN  = GND
  DD83  VCCFA_EHV_FIVRA47  POWER  = PVCCFA_EHV_FIVRA_CPU1
  DD85  VCCFA_EHV_FIVRA48  POWER  = PVCCFA_EHV_FIVRA_CPU1
  DD87  PE3_TX_DN10  OUT  = P5E_CPU1_PE3_TX_DN<10>
  DD89  VCCFA_EHV_FIVRA49  POWER  = PVCCFA_EHV_FIVRA_CPU1
  DD91  PE3_RX_DN11  IN  = P5E_CPU1_PE3_RX_DN<11>
  DE1  UPI1_RX_DN11  IN  = UPI_CPU0_CPU1_P0P1_DN<11>
  DE3  VCCINFAON29  POWER  = PVCCINFAON_CPU1
  DE5  UPI1_TX_DN10  OUT  = UPI_CPU1_CPU0_P1P0_DN<10>
  DE7  VCCINFAON58  POWER  = PVCCINFAON_CPU1
  DE9  PE2_RX_DN4  IN  = P5E_CPU1_PE2_RX_DN<4>
  DE11  VCCINFAON27  POWER  = PVCCINFAON_CPU1
  DE13  PE2_TX_DN4  OUT  = P5E_CPU1_PE2_TX_DN<4>
  DE15  VCCINFAON28  POWER  = PVCCINFAON_CPU1
  DE17  VSS970  POWER  = GND
  DE19  VSS971  POWER  = GND
  DE21  VSS972  POWER  = GND
  DE23  VSS974  POWER  = GND
  DE25  VSS975  POWER  = GND
  DE27  VSS977  POWER  = GND
  DE29  VSS978  POWER  = GND
  DE31  VSS981  POWER  = GND
  DE33  VSS982  POWER  = GND
  DE35  VSS983  POWER  = GND
  DE37  VSS984  POWER  = GND
  DE39  VSS776  POWER  = GND
  DE41  VSS986  POWER  = GND
  DE43  VSS987  POWER  = GND
  DE45  VSS988  POWER  = GND
  DE48  VSS989  POWER  = GND
  DE50  VSS991  POWER  = GND
  DE52  VSS992  POWER  = GND
  DE54  VSS994  POWER  = GND
  DE56  VSS995  POWER  = GND
  DE58  VSS996  POWER  = GND
  DE60  VSS997  POWER  = GND
  DE62  VSS999  POWER  = GND
  DE64  VSS1001  POWER  = GND
  DE66  VSS1004  POWER  = GND
  DE68  VSS1007  POWER  = GND
  DE70  VSS791  POWER  = GND
  DE72  VSS1008  POWER  = GND
  DE74  VSS1009  POWER  = GND
  DE76  VSS1010  POWER  = GND
  DE78  UPI3_RX_DP16  IN  = GND
  DE80  UPI3_RX_DN13  IN  = GND
  DE82  VSS1011  POWER  = GND
  DE84  VSS1012  POWER  = GND
  DE86  PE3_TX_DP10  OUT  = P5E_CPU1_PE3_TX_DP<10>
  DE88  VSS1015  POWER  = GND
  DE90  PE3_RX_DP11  IN  = P5E_CPU1_PE3_RX_DP<11>
  DF2  UPI1_RX_DP11  IN  = UPI_CPU0_CPU1_P0P1_DP<11>
